(kicad_pcb
	(version 20260206)
	(generator "pcbnew")
	(generator_version "10.0")
	(general
		(thickness 1.6)
		(legacy_teardrops no)
	)
	(paper "A4")
	(title_block
		(title "Wiwynn_Tioga_Pass_MB.brd")
		(comment 1 "Tioga Pass / footprints 2403-2409 of 4770")
	)
	(layers
		(0 "F.Cu" signal "TOP")
		(4 "In1.Cu" signal "L2GND")
		(6 "In2.Cu" signal "L3")
		(8 "In3.Cu" signal "L4GND")
		(10 "In4.Cu" signal "L5")
		(12 "In5.Cu" signal "L6GND")
		(14 "In6.Cu" signal "L7VCC")
		(16 "In7.Cu" signal "L8VCC")
		(18 "In8.Cu" signal "L9GND")
		(20 "In9.Cu" signal "L10")
		(22 "In10.Cu" signal "L11GND")
		(24 "In11.Cu" signal "L12")
		(26 "In12.Cu" signal "L13GND")
		(2 "B.Cu" signal "BOTTOM")
		(9 "F.Adhes" user "F.Adhesive")
		(11 "B.Adhes" user "B.Adhesive")
		(13 "F.Paste" user "Package Geometry/Pastemask Top")
		(15 "B.Paste" user "Package Geometry/Pastemask Bottom")
		(5 "F.SilkS" user "Ref Des/Silkscreen Top")
		(7 "B.SilkS" user "Ref Des/Silkscreen Bottom")
		(1 "F.Mask" user "Board Geometry/Soldermask Top")
		(3 "B.Mask" user "Board Geometry/Soldermask Bottom")
		(17 "Dwgs.User" user "User.Drawings")
		(19 "Cmts.User" user "User.Comments")
		(21 "Eco1.User" user "User.Eco1")
		(23 "Eco2.User" user "User.Eco2")
		(25 "Edge.Cuts" user "Board Geometry/Outline")
		(27 "Margin" user)
		(31 "F.CrtYd" user "Package Geometry/Place Bound Top")
		(29 "B.CrtYd" user "Package Geometry/Place Bound Bottom")
		(35 "F.Fab" user "Ref Des/Assembly Top")
		(33 "B.Fab" user "Ref Des/Assembly Bottom")
	)
	(footprint ""
		(layer "B.Cu")
		(at 367.646712 -37.856922)
		(property "Reference" "R8F13"
			(at 0 0 0)
			(layer "B.SilkS")
			(hide yes)
			(effects
				(font
					(size 1.27 1.27)
				)
				(justify mirror)
			)
		)
		(property "Value" ""
			(at 0 0 0)
			(layer "B.Fab")
			(effects
				(font
					(size 1.27 1.27)
				)
				(justify mirror)
			)
		)
		(duplicate_pad_numbers_are_jumpers no)
		(fp_poly
			(pts
				(xy 0.2794 -0.1016) (xy -0.2794 -0.1016) (xy -0.2794 0.9906) (xy 0.2794 0.9906)
			)
			(stroke
				(width 0)
				(type default)
			)
			(fill no)
			(layer "B.CrtYd")
		)
		(fp_line
			(start -0.2794 -0.1016)
			(end 0.2794 -0.1016)
			(stroke
				(width 0.1)
				(type default)
			)
			(layer "B.Fab")
		)
		(fp_line
			(start -0.2794 0.9906)
			(end -0.2794 -0.1016)
			(stroke
				(width 0.1)
				(type default)
			)
			(layer "B.Fab")
		)
		(fp_line
			(start 0.2794 -0.1016)
			(end 0.2794 0.9906)
			(stroke
				(width 0.1)
				(type default)
			)
			(layer "B.Fab")
		)
		(fp_line
			(start 0.2794 0.9906)
			(end -0.2794 0.9906)
			(stroke
				(width 0.1)
				(type default)
			)
			(layer "B.Fab")
		)
		(pad "1" smd rect
			(at 0 0 180)
			(size 0.508 0.508)
			(layers "B.Cu" "B.Mask" "B.Paste")
			(net "P3V3_STBY")
		)
		(pad "2" smd rect
			(at 0 0.889 180)
			(size 0.508 0.508)
			(layers "B.Cu" "B.Mask" "B.Paste")
			(net "SPI_BMC_BT_CS_N")
		)
		(zone
			(layer "B.Cu")
			(hatch none 0.5)
			(connect_pads
				(clearance 0)
			)
			(min_thickness 0.25)
			(keepout
				(tracks allowed)
				(vias not_allowed)
				(pads allowed)
				(copperpour not_allowed)
				(footprints allowed)
			)
			(placement
				(enabled no)
				(sheetname "")
			)
			(fill
				(thermal_gap 0.5)
				(thermal_bridge_width 0.5)
				(island_removal_mode 0)
			)
			(polygon
				(pts
					(xy 367.900712 -37.602922) (xy 367.392712 -37.602922) (xy 367.392712 -37.221922) (xy 367.900712 -37.221922)
				)
			)
		)
		(zone
			(layer "B.Cu")
			(hatch none 0.5)
			(connect_pads
				(clearance 0)
			)
			(min_thickness 0.25)
			(keepout
				(tracks not_allowed)
				(vias allowed)
				(pads allowed)
				(copperpour not_allowed)
				(footprints allowed)
			)
			(placement
				(enabled no)
				(sheetname "")
			)
			(fill
				(thermal_gap 0.5)
				(thermal_bridge_width 0.5)
				(island_removal_mode 0)
			)
			(polygon
				(pts
					(xy 367.900712 -37.221922) (xy 367.392712 -37.221922) (xy 367.392712 -37.602922) (xy 367.900712 -37.602922)
				)
			)
		)
	)
	(footprint ""
		(layer "B.Cu")
		(at 454.453752 -144.455896)
		(property "Reference" "R9A17"
			(at 0 0 0)
			(layer "B.SilkS")
			(hide yes)
			(effects
				(font
					(size 1.27 1.27)
				)
				(justify mirror)
			)
		)
		(property "Value" ""
			(at 0 0 0)
			(layer "B.Fab")
			(effects
				(font
					(size 1.27 1.27)
				)
				(justify mirror)
			)
		)
		(duplicate_pad_numbers_are_jumpers no)
		(fp_poly
			(pts
				(xy 0.2794 -0.1016) (xy -0.2794 -0.1016) (xy -0.2794 0.9906) (xy 0.2794 0.9906)
			)
			(stroke
				(width 0)
				(type default)
			)
			(fill no)
			(layer "B.CrtYd")
		)
		(fp_line
			(start -0.2794 -0.1016)
			(end 0.2794 -0.1016)
			(stroke
				(width 0.1)
				(type default)
			)
			(layer "B.Fab")
		)
		(fp_line
			(start -0.2794 0.9906)
			(end -0.2794 -0.1016)
			(stroke
				(width 0.1)
				(type default)
			)
			(layer "B.Fab")
		)
		(fp_line
			(start 0.2794 -0.1016)
			(end 0.2794 0.9906)
			(stroke
				(width 0.1)
				(type default)
			)
			(layer "B.Fab")
		)
		(fp_line
			(start 0.2794 0.9906)
			(end -0.2794 0.9906)
			(stroke
				(width 0.1)
				(type default)
			)
			(layer "B.Fab")
		)
		(pad "1" smd rect
			(at 0 0 180)
			(size 0.508 0.508)
			(layers "B.Cu" "B.Mask" "B.Paste")
			(net "XDP_ITP_PMODE")
		)
		(pad "2" smd rect
			(at 0 0.889 180)
			(size 0.508 0.508)
			(layers "B.Cu" "B.Mask" "B.Paste")
			(net "P1V05_PCH_STBY")
		)
		(zone
			(layer "B.Cu")
			(hatch none 0.5)
			(connect_pads
				(clearance 0)
			)
			(min_thickness 0.25)
			(keepout
				(tracks allowed)
				(vias not_allowed)
				(pads allowed)
				(copperpour not_allowed)
				(footprints allowed)
			)
			(placement
				(enabled no)
				(sheetname "")
			)
			(fill
				(thermal_gap 0.5)
				(thermal_bridge_width 0.5)
				(island_removal_mode 0)
			)
			(polygon
				(pts
					(xy 454.707752 -144.201896) (xy 454.199752 -144.201896) (xy 454.199752 -143.820896) (xy 454.707752 -143.820896)
				)
			)
		)
		(zone
			(layer "B.Cu")
			(hatch none 0.5)
			(connect_pads
				(clearance 0)
			)
			(min_thickness 0.25)
			(keepout
				(tracks not_allowed)
				(vias allowed)
				(pads allowed)
				(copperpour not_allowed)
				(footprints allowed)
			)
			(placement
				(enabled no)
				(sheetname "")
			)
			(fill
				(thermal_gap 0.5)
				(thermal_bridge_width 0.5)
				(island_removal_mode 0)
			)
			(polygon
				(pts
					(xy 454.707752 -143.820896) (xy 454.199752 -143.820896) (xy 454.199752 -144.201896) (xy 454.707752 -144.201896)
				)
			)
		)
	)
	(footprint ""
		(layer "B.Cu")
		(at 385.572 -49.403 90)
		(property "Reference" "R3U1"
			(at 0 0 90)
			(layer "B.SilkS")
			(hide yes)
			(effects
				(font
					(size 1.27 1.27)
				)
				(justify mirror)
			)
		)
		(property "Value" ""
			(at 0 0 90)
			(layer "B.Fab")
			(effects
				(font
					(size 1.27 1.27)
				)
				(justify mirror)
			)
		)
		(duplicate_pad_numbers_are_jumpers no)
		(fp_poly
			(pts
				(xy 0.2794 -0.1016) (xy -0.2794 -0.1016) (xy -0.2794 0.9906) (xy 0.2794 0.9906)
			)
			(stroke
				(width 0)
				(type default)
			)
			(fill no)
			(layer "B.CrtYd")
		)
		(fp_line
			(start 0.2794 -0.1016)
			(end 0.2794 0.9906)
			(stroke
				(width 0.1)
				(type default)
			)
			(layer "B.Fab")
		)
		(fp_line
			(start -0.2794 -0.1016)
			(end 0.2794 -0.1016)
			(stroke
				(width 0.1)
				(type default)
			)
			(layer "B.Fab")
		)
		(fp_line
			(start 0.2794 0.9906)
			(end -0.2794 0.9906)
			(stroke
				(width 0.1)
				(type default)
			)
			(layer "B.Fab")
		)
		(fp_line
			(start -0.2794 0.9906)
			(end -0.2794 -0.1016)
			(stroke
				(width 0.1)
				(type default)
			)
			(layer "B.Fab")
		)
		(pad "1" smd rect
			(at 0 0 270)
			(size 0.508 0.508)
			(layers "B.Cu" "B.Mask" "B.Paste")
			(net "SPI_BIOS_SOCKET_IO2")
		)
		(pad "2" smd rect
			(at 0 0.889 270)
			(size 0.508 0.508)
			(layers "B.Cu" "B.Mask" "B.Paste")
			(net "PU_BIOS_SPI_WP1_N")
		)
		(zone
			(layer "B.Cu")
			(hatch none 0.5)
			(connect_pads
				(clearance 0)
			)
			(min_thickness 0.25)
			(keepout
				(tracks allowed)
				(vias not_allowed)
				(pads allowed)
				(copperpour not_allowed)
				(footprints allowed)
			)
			(placement
				(enabled no)
				(sheetname "")
			)
			(fill
				(thermal_gap 0.5)
				(thermal_bridge_width 0.5)
				(island_removal_mode 0)
			)
			(polygon
				(pts
					(xy 385.826 -49.657) (xy 385.826 -49.149) (xy 386.207 -49.149) (xy 386.207 -49.657)
				)
			)
		)
		(zone
			(layer "B.Cu")
			(hatch none 0.5)
			(connect_pads
				(clearance 0)
			)
			(min_thickness 0.25)
			(keepout
				(tracks not_allowed)
				(vias allowed)
				(pads allowed)
				(copperpour not_allowed)
				(footprints allowed)
			)
			(placement
				(enabled no)
				(sheetname "")
			)
			(fill
				(thermal_gap 0.5)
				(thermal_bridge_width 0.5)
				(island_removal_mode 0)
			)
			(polygon
				(pts
					(xy 386.207 -49.657) (xy 386.207 -49.149) (xy 385.826 -49.149) (xy 385.826 -49.657)
				)
			)
		)
	)
	(footprint ""
		(layer "B.Cu")
		(at 205.74 -104.775 -90)
		(property "Reference" "R6N12"
			(at 0 0 90)
			(layer "B.SilkS")
			(hide yes)
			(effects
				(font
					(size 1.27 1.27)
				)
				(justify mirror)
			)
		)
		(property "Value" ""
			(at 0 0 90)
			(layer "B.Fab")
			(effects
				(font
					(size 1.27 1.27)
				)
				(justify mirror)
			)
		)
		(duplicate_pad_numbers_are_jumpers no)
		(fp_poly
			(pts
				(xy 0.2794 -0.1016) (xy -0.2794 -0.1016) (xy -0.2794 0.9906) (xy 0.2794 0.9906)
			)
			(stroke
				(width 0)
				(type default)
			)
			(fill no)
			(layer "B.CrtYd")
		)
		(fp_line
			(start -0.2794 0.9906)
			(end -0.2794 -0.1016)
			(stroke
				(width 0.1)
				(type default)
			)
			(layer "B.Fab")
		)
		(fp_line
			(start 0.2794 0.9906)
			(end -0.2794 0.9906)
			(stroke
				(width 0.1)
				(type default)
			)
			(layer "B.Fab")
		)
		(fp_line
			(start -0.2794 -0.1016)
			(end 0.2794 -0.1016)
			(stroke
				(width 0.1)
				(type default)
			)
			(layer "B.Fab")
		)
		(fp_line
			(start 0.2794 -0.1016)
			(end 0.2794 0.9906)
			(stroke
				(width 0.1)
				(type default)
			)
			(layer "B.Fab")
		)
		(pad "1" smd rect
			(at 0 0 90)
			(size 0.508 0.508)
			(layers "B.Cu" "B.Mask" "B.Paste")
			(net "SVID_CLK0_CPU0")
		)
		(pad "2" smd rect
			(at 0 0.889 90)
			(size 0.508 0.508)
			(layers "B.Cu" "B.Mask" "B.Paste")
			(net "SVID_CLK0_CPU0_R")
		)
		(zone
			(layer "B.Cu")
			(hatch none 0.5)
			(connect_pads
				(clearance 0)
			)
			(min_thickness 0.25)
			(keepout
				(tracks not_allowed)
				(vias allowed)
				(pads allowed)
				(copperpour not_allowed)
				(footprints allowed)
			)
			(placement
				(enabled no)
				(sheetname "")
			)
			(fill
				(thermal_gap 0.5)
				(thermal_bridge_width 0.5)
				(island_removal_mode 0)
			)
			(polygon
				(pts
					(xy 205.105 -104.521) (xy 205.105 -105.029) (xy 205.486 -105.029) (xy 205.486 -104.521)
				)
			)
		)
		(zone
			(layer "B.Cu")
			(hatch none 0.5)
			(connect_pads
				(clearance 0)
			)
			(min_thickness 0.25)
			(keepout
				(tracks allowed)
				(vias not_allowed)
				(pads allowed)
				(copperpour not_allowed)
				(footprints allowed)
			)
			(placement
				(enabled no)
				(sheetname "")
			)
			(fill
				(thermal_gap 0.5)
				(thermal_bridge_width 0.5)
				(island_removal_mode 0)
			)
			(polygon
				(pts
					(xy 205.486 -104.521) (xy 205.486 -105.029) (xy 205.105 -105.029) (xy 205.105 -104.521)
				)
			)
		)
	)
	(footprint ""
		(layer "B.Cu")
		(at 83.856068 -145.0086 -90)
		(property "Reference" "C8L9"
			(at -1.848866 0.752348 270)
			(unlocked yes)
			(layer "B.SilkS")
			(effects
				(font
					(size 1.27 0.9652)
					(thickness 0.1524)
				)
				(justify mirror)
			)
		)
		(property "Value" ""
			(at 0 0 90)
			(layer "B.Fab")
			(effects
				(font
					(size 1.27 1.27)
				)
				(justify mirror)
			)
		)
		(duplicate_pad_numbers_are_jumpers no)
		(fp_rect
			(start 0.500126 1.598422)
			(end -0.500126 -0.201422)
			(stroke
				(width 0)
				(type default)
			)
			(fill no)
			(layer "B.CrtYd")
		)
		(fp_line
			(start -0.500126 1.598422)
			(end 0.500126 1.598422)
			(stroke
				(width 0.1)
				(type default)
			)
			(layer "B.Fab")
		)
		(fp_line
			(start 0.500126 1.598422)
			(end 0.500126 -0.201422)
			(stroke
				(width 0.1)
				(type default)
			)
			(layer "B.Fab")
		)
		(fp_line
			(start -0.500126 -0.201422)
			(end -0.500126 1.598422)
			(stroke
				(width 0.1)
				(type default)
			)
			(layer "B.Fab")
		)
		(fp_line
			(start 0.500126 -0.201422)
			(end -0.500126 -0.201422)
			(stroke
				(width 0.1)
				(type default)
			)
			(layer "B.Fab")
		)
		(pad "1" smd rect
			(at 0 0 180)
			(size 0.889 0.9906)
			(layers "B.Cu" "B.Mask" "B.Paste")
			(net "PVDDQ_KLM")
		)
		(pad "2" smd rect
			(at 0 1.397 180)
			(size 0.889 0.9906)
			(layers "B.Cu" "B.Mask" "B.Paste")
			(net "GND")
		)
		(zone
			(layer "B.Cu")
			(hatch none 0.5)
			(connect_pads
				(clearance 0)
			)
			(min_thickness 0.25)
			(keepout
				(tracks allowed)
				(vias not_allowed)
				(pads allowed)
				(copperpour not_allowed)
				(footprints allowed)
			)
			(placement
				(enabled no)
				(sheetname "")
			)
			(fill
				(thermal_gap 0.5)
				(thermal_bridge_width 0.5)
				(island_removal_mode 0)
			)
			(polygon
				(pts
					(xy 82.903568 -144.5133) (xy 83.411568 -144.5133) (xy 83.411568 -145.5039) (xy 82.903568 -145.5039)
				)
			)
		)
		(zone
			(layer "B.Cu")
			(hatch none 0.5)
			(connect_pads
				(clearance 0)
			)
			(min_thickness 0.25)
			(keepout
				(tracks not_allowed)
				(vias allowed)
				(pads allowed)
				(copperpour not_allowed)
				(footprints allowed)
			)
			(placement
				(enabled no)
				(sheetname "")
			)
			(fill
				(thermal_gap 0.5)
				(thermal_bridge_width 0.5)
				(island_removal_mode 0)
			)
			(polygon
				(pts
					(xy 82.903568 -144.5133) (xy 83.411568 -144.5133) (xy 83.411568 -145.5039) (xy 82.903568 -145.5039)
				)
			)
		)
	)
	(footprint ""
		(layer "B.Cu")
		(at 400.756628 -117.179344)
		(property "Reference" "R7W8"
			(at 0.8382 -0.67818 0)
			(unlocked yes)
			(layer "B.SilkS")
			(effects
				(font
					(size 0.4064 0.254)
					(thickness 0.1524)
				)
				(justify left mirror)
			)
		)
		(property "Value" ""
			(at 0 0 0)
			(layer "B.Fab")
			(effects
				(font
					(size 1.27 1.27)
				)
				(justify mirror)
			)
		)
		(duplicate_pad_numbers_are_jumpers no)
		(fp_poly
			(pts
				(xy 0.2794 -0.1016) (xy -0.2794 -0.1016) (xy -0.2794 0.9906) (xy 0.2794 0.9906)
			)
			(stroke
				(width 0)
				(type default)
			)
			(fill no)
			(layer "B.CrtYd")
		)
		(fp_line
			(start -0.2794 -0.1016)
			(end 0.2794 -0.1016)
			(stroke
				(width 0.1)
				(type default)
			)
			(layer "B.Fab")
		)
		(fp_line
			(start -0.2794 0.9906)
			(end -0.2794 -0.1016)
			(stroke
				(width 0.1)
				(type default)
			)
			(layer "B.Fab")
		)
		(fp_line
			(start 0.2794 -0.1016)
			(end 0.2794 0.9906)
			(stroke
				(width 0.1)
				(type default)
			)
			(layer "B.Fab")
		)
		(fp_line
			(start 0.2794 0.9906)
			(end -0.2794 0.9906)
			(stroke
				(width 0.1)
				(type default)
			)
			(layer "B.Fab")
		)
		(pad "1" smd rect
			(at 0 0 180)
			(size 0.508 0.508)
			(layers "B.Cu" "B.Mask" "B.Paste")
			(net "FM_POST_CARD_PRES_BMC_N")
		)
		(pad "2" smd rect
			(at 0 0.889 180)
			(size 0.508 0.508)
			(layers "B.Cu" "B.Mask" "B.Paste")
			(net "FM_POST_CARD_PRES_BMC_R1_N")
		)
		(zone
			(layer "B.Cu")
			(hatch none 0.5)
			(connect_pads
				(clearance 0)
			)
			(min_thickness 0.25)
			(keepout
				(tracks allowed)
				(vias not_allowed)
				(pads allowed)
				(copperpour not_allowed)
				(footprints allowed)
			)
			(placement
				(enabled no)
				(sheetname "")
			)
			(fill
				(thermal_gap 0.5)
				(thermal_bridge_width 0.5)
				(island_removal_mode 0)
			)
			(polygon
				(pts
					(xy 401.010628 -116.925344) (xy 400.502628 -116.925344) (xy 400.502628 -116.544344) (xy 401.010628 -116.544344)
				)
			)
		)
		(zone
			(layer "B.Cu")
			(hatch none 0.5)
			(connect_pads
				(clearance 0)
			)
			(min_thickness 0.25)
			(keepout
				(tracks not_allowed)
				(vias allowed)
				(pads allowed)
				(copperpour not_allowed)
				(footprints allowed)
			)
			(placement
				(enabled no)
				(sheetname "")
			)
			(fill
				(thermal_gap 0.5)
				(thermal_bridge_width 0.5)
				(island_removal_mode 0)
			)
			(polygon
				(pts
					(xy 401.010628 -116.544344) (xy 400.502628 -116.544344) (xy 400.502628 -116.925344) (xy 401.010628 -116.925344)
				)
			)
		)
	)
	(footprint ""
		(layer "B.Cu")
		(at 165.9001 4.445 180)
		(property "Reference" "R6U18"
			(at 0 0 0)
			(layer "B.SilkS")
			(hide yes)
			(effects
				(font
					(size 1.27 1.27)
				)
				(justify mirror)
			)
		)
		(property "Value" ""
			(at 0 0 0)
			(layer "B.Fab")
			(effects
				(font
					(size 1.27 1.27)
				)
				(justify mirror)
			)
		)
		(duplicate_pad_numbers_are_jumpers no)
		(fp_poly
			(pts
				(xy 0.2794 -0.1016) (xy -0.2794 -0.1016) (xy -0.2794 0.9906) (xy 0.2794 0.9906)
			)
			(stroke
				(width 0)
				(type default)
			)
			(fill no)
			(layer "B.CrtYd")
		)
		(fp_line
			(start 0.2794 0.9906)
			(end -0.2794 0.9906)
			(stroke
				(width 0.1)
				(type default)
			)
			(layer "B.Fab")
		)
		(fp_line
			(start 0.2794 -0.1016)
			(end 0.2794 0.9906)
			(stroke
				(width 0.1)
				(type default)
			)
			(layer "B.Fab")
		)
		(fp_line
			(start -0.2794 0.9906)
			(end -0.2794 -0.1016)
			(stroke
				(width 0.1)
				(type default)
			)
			(layer "B.Fab")
		)
		(fp_line
			(start -0.2794 -0.1016)
			(end 0.2794 -0.1016)
			(stroke
				(width 0.1)
				(type default)
			)
			(layer "B.Fab")
		)
		(pad "1" smd rect
			(at 0 0)
			(size 0.508 0.508)
			(layers "B.Cu" "B.Mask" "B.Paste")
			(net "PVPP_GHJ")
		)
		(pad "2" smd rect
			(at 0 0.889)
			(size 0.508 0.508)
			(layers "B.Cu" "B.Mask" "B.Paste")
			(net "SMB_DDR_GHJ_VPP_SDA_R")
		)
		(zone
			(layer "B.Cu")
			(hatch none 0.5)
			(connect_pads
				(clearance 0)
			)
			(min_thickness 0.25)
			(keepout
				(tracks not_allowed)
				(vias allowed)
				(pads allowed)
				(copperpour not_allowed)
				(footprints allowed)
			)
			(placement
				(enabled no)
				(sheetname "")
			)
			(fill
				(thermal_gap 0.5)
				(thermal_bridge_width 0.5)
				(island_removal_mode 0)
			)
			(polygon
				(pts
					(xy 165.6461 3.81) (xy 166.1541 3.81) (xy 166.1541 4.191) (xy 165.6461 4.191)
				)
			)
		)
		(zone
			(layer "B.Cu")
			(hatch none 0.5)
			(connect_pads
				(clearance 0)
			)
			(min_thickness 0.25)
			(keepout
				(tracks allowed)
				(vias not_allowed)
				(pads allowed)
				(copperpour not_allowed)
				(footprints allowed)
			)
			(placement
				(enabled no)
				(sheetname "")
			)
			(fill
				(thermal_gap 0.5)
				(thermal_bridge_width 0.5)
				(island_removal_mode 0)
			)
			(polygon
				(pts
					(xy 165.6461 4.191) (xy 166.1541 4.191) (xy 166.1541 3.81) (xy 165.6461 3.81)
				)
			)
		)
	)
)
